# SCM (Grand Teton) — schematic netlist excerpt (pin names and nets, part order shuffled) for the footprints in the layout excerpt that follows; sources: Cadence DE-HDL packaged netlist, KiCad conversion of 12092022_DA0F0TMDCD0_F0T_Management_Board_D_brd_V3_OCP.brd

R310  Q_RES  33.2 1% CHIP  pkg 0402LF  page 12 : A = ESPI_HOST_LPC_BMC_CLK ; B = ESPI_HOST_LPC_BMC_CLK_R
R212  Q_RES  4.7K 1% CHIP  pkg 0402LF  page 15 : A = P3V3_RGM ; B = PU_25M_BMC_CLK_EN

(kicad_pcb
	(version 20260206)
	(generator "pcbnew")
	(generator_version "10.0")
	(general
		(thickness 1.6)
		(legacy_teardrops no)
	)
	(paper "A4")
	(title_block
		(title "12092022_DA0F0TMDCD0_F0T_Management_Board_D_brd_V3_OCP.brd")
		(comment 1 "Grand Teton / footprints 575-576 of 1440")
	)
	(layers
		(0 "F.Cu" signal "TOP")
		(4 "In1.Cu" signal "GND")
		(6 "In2.Cu" signal "IN1")
		(8 "In3.Cu" signal "GND1")
		(10 "In4.Cu" signal "IN2")
		(12 "In5.Cu" signal "VCC")
		(14 "In6.Cu" signal "VCC1")
		(16 "In7.Cu" signal "IN3")
		(18 "In8.Cu" signal "GND2")
		(20 "In9.Cu" signal "IN4")
		(22 "In10.Cu" signal "GND3")
		(2 "B.Cu" signal "BOTTOM")
		(9 "F.Adhes" user "F.Adhesive")
		(11 "B.Adhes" user "B.Adhesive")
		(13 "F.Paste" user "Package Geometry/Pastemask Top")
		(15 "B.Paste" user "Package Geometry/Pastemask Bottom")
		(5 "F.SilkS" user "Ref Des/Silkscreen Top")
		(7 "B.SilkS" user "Ref Des/Silkscreen Bottom")
		(1 "F.Mask" user "Board Geometry/Soldermask Top")
		(3 "B.Mask" user "Board Geometry/Soldermask Bottom")
		(17 "Dwgs.User" user "User.Drawings")
		(19 "Cmts.User" user "User.Comments")
		(21 "Eco1.User" user "User.Eco1")
		(23 "Eco2.User" user "User.Eco2")
		(25 "Edge.Cuts" user "Board Geometry/Outline")
		(27 "Margin" user)
		(31 "F.CrtYd" user "Package Geometry/Place Bound Top")
		(29 "B.CrtYd" user "Package Geometry/Place Bound Bottom")
		(35 "F.Fab" user "Ref Des/Assembly Top")
		(33 "B.Fab" user "Ref Des/Assembly Bottom")
	)
	(footprint ""
		(layer "F.Cu")
		(at 66.5226 -108.0008 -90)
		(property "Reference" "R310"
			(at 0 0 270)
			(layer "F.SilkS")
			(hide yes)
			(effects
				(font
					(size 1.27 1.27)
				)
			)
		)
		(property "Value" ""
			(at 0 0 270)
			(layer "F.Fab")
			(effects
				(font
					(size 1.27 1.27)
				)
			)
		)
		(duplicate_pad_numbers_are_jumpers no)
		(fp_line
			(start -0.7874 0.4064)
			(end -0.7874 -0.4064)
			(stroke
				(width 0.1524)
				(type default)
			)
			(layer "F.SilkS")
		)
		(fp_line
			(start 0.7874 0.4064)
			(end -0.7874 0.4064)
			(stroke
				(width 0.1524)
				(type default)
			)
			(layer "F.SilkS")
		)
		(fp_line
			(start -0.7874 -0.4064)
			(end 0.7874 -0.4064)
			(stroke
				(width 0.1524)
				(type default)
			)
			(layer "F.SilkS")
		)
		(fp_line
			(start 0.7874 -0.4064)
			(end 0.7874 0.4064)
			(stroke
				(width 0.1524)
				(type default)
			)
			(layer "F.SilkS")
		)
		(fp_line
			(start -0.67945 0.3048)
			(end -0.67945 -0.305054)
			(stroke
				(width 0.1)
				(type default)
			)
			(layer "F.Fab")
		)
		(fp_line
			(start -0.12065 0.3048)
			(end -0.67945 0.3048)
			(stroke
				(width 0.1)
				(type default)
			)
			(layer "F.Fab")
		)
		(fp_line
			(start 0.120396 0.3048)
			(end 0.120396 0.2794)
			(stroke
				(width 0.1)
				(type default)
			)
			(layer "F.Fab")
		)
		(fp_line
			(start 0.67945 0.3048)
			(end 0.120396 0.3048)
			(stroke
				(width 0.1)
				(type default)
			)
			(layer "F.Fab")
		)
		(fp_line
			(start -0.12065 0.2794)
			(end -0.12065 0.3048)
			(stroke
				(width 0.1)
				(type default)
			)
			(layer "F.Fab")
		)
		(fp_line
			(start 0.120396 0.2794)
			(end -0.12065 0.2794)
			(stroke
				(width 0.1)
				(type default)
			)
			(layer "F.Fab")
		)
		(fp_line
			(start -0.12065 -0.2794)
			(end 0.12065 -0.2794)
			(stroke
				(width 0.1)
				(type default)
			)
			(layer "F.Fab")
		)
		(fp_line
			(start 0.12065 -0.2794)
			(end 0.12065 -0.3048)
			(stroke
				(width 0.1)
				(type default)
			)
			(layer "F.Fab")
		)
		(fp_line
			(start 0.12065 -0.3048)
			(end 0.67945 -0.3048)
			(stroke
				(width 0.1)
				(type default)
			)
			(layer "F.Fab")
		)
		(fp_line
			(start 0.67945 -0.3048)
			(end 0.67945 0.3048)
			(stroke
				(width 0.1)
				(type default)
			)
			(layer "F.Fab")
		)
		(fp_line
			(start -0.67945 -0.305054)
			(end -0.12065 -0.305054)
			(stroke
				(width 0.1)
				(type default)
			)
			(layer "F.Fab")
		)
		(fp_line
			(start -0.12065 -0.305054)
			(end -0.12065 -0.2794)
			(stroke
				(width 0.1)
				(type default)
			)
			(layer "F.Fab")
		)
		(pad "1" smd circle
			(at -0.40005 0 270)
			(size 0 0)
			(layers "F.Cu" "F.Mask" "F.Paste")
			(net "ESPI_HOST_LPC_BMC_CLK")
		)
		(pad "2" smd circle
			(at 0.40005 0 270)
			(size 0 0)
			(layers "F.Cu" "F.Mask" "F.Paste")
			(net "ESPI_HOST_LPC_BMC_CLK_R")
		)
	)
	(footprint ""
		(layer "F.Cu")
		(at 54.55539 -28.026868 -90)
		(property "Reference" "R212"
			(at 0 0 270)
			(layer "F.SilkS")
			(hide yes)
			(effects
				(font
					(size 1.27 1.27)
				)
			)
		)
		(property "Value" ""
			(at 0 0 270)
			(layer "F.Fab")
			(effects
				(font
					(size 1.27 1.27)
				)
			)
		)
		(duplicate_pad_numbers_are_jumpers no)
		(fp_line
			(start -0.7874 0.4064)
			(end -0.7874 -0.4064)
			(stroke
				(width 0.1524)
				(type default)
			)
			(layer "F.SilkS")
		)
		(fp_line
			(start 0.7874 0.4064)
			(end -0.7874 0.4064)
			(stroke
				(width 0.1524)
				(type default)
			)
			(layer "F.SilkS")
		)
		(fp_line
			(start -0.7874 -0.4064)
			(end 0.7874 -0.4064)
			(stroke
				(width 0.1524)
				(type default)
			)
			(layer "F.SilkS")
		)
		(fp_line
			(start 0.7874 -0.4064)
			(end 0.7874 0.4064)
			(stroke
				(width 0.1524)
				(type default)
			)
			(layer "F.SilkS")
		)
		(fp_line
			(start -0.67945 0.3048)
			(end -0.67945 -0.305054)
			(stroke
				(width 0.1)
				(type default)
			)
			(layer "F.Fab")
		)
		(fp_line
			(start -0.12065 0.3048)
			(end -0.67945 0.3048)
			(stroke
				(width 0.1)
				(type default)
			)
			(layer "F.Fab")
		)
		(fp_line
			(start 0.120396 0.3048)
			(end 0.120396 0.2794)
			(stroke
				(width 0.1)
				(type default)
			)
			(layer "F.Fab")
		)
		(fp_line
			(start 0.67945 0.3048)
			(end 0.120396 0.3048)
			(stroke
				(width 0.1)
				(type default)
			)
			(layer "F.Fab")
		)
		(fp_line
			(start -0.12065 0.2794)
			(end -0.12065 0.3048)
			(stroke
				(width 0.1)
				(type default)
			)
			(layer "F.Fab")
		)
		(fp_line
			(start 0.120396 0.2794)
			(end -0.12065 0.2794)
			(stroke
				(width 0.1)
				(type default)
			)
			(layer "F.Fab")
		)
		(fp_line
			(start -0.12065 -0.2794)
			(end 0.12065 -0.2794)
			(stroke
				(width 0.1)
				(type default)
			)
			(layer "F.Fab")
		)
		(fp_line
			(start 0.12065 -0.2794)
			(end 0.12065 -0.3048)
			(stroke
				(width 0.1)
				(type default)
			)
			(layer "F.Fab")
		)
		(fp_line
			(start 0.12065 -0.3048)
			(end 0.67945 -0.3048)
			(stroke
				(width 0.1)
				(type default)
			)
			(layer "F.Fab")
		)
		(fp_line
			(start 0.67945 -0.3048)
			(end 0.67945 0.3048)
			(stroke
				(width 0.1)
				(type default)
			)
			(layer "F.Fab")
		)
		(fp_line
			(start -0.67945 -0.305054)
			(end -0.12065 -0.305054)
			(stroke
				(width 0.1)
				(type default)
			)
			(layer "F.Fab")
		)
		(fp_line
			(start -0.12065 -0.305054)
			(end -0.12065 -0.2794)
			(stroke
				(width 0.1)
				(type default)
			)
			(layer "F.Fab")
		)
		(pad "1" smd circle
			(at -0.40005 0 270)
			(size 0 0)
			(layers "F.Cu" "F.Mask" "F.Paste")
			(net "P3V3_RGM")
		)
		(pad "2" smd circle
			(at 0.40005 0 270)
			(size 0 0)
			(layers "F.Cu" "F.Mask" "F.Paste")
			(net "PU_25M_BMC_CLK_EN")
		)
	)
)
